# S9S_MB_2U (Grand Teton) — schematic netlist excerpt (pin names and nets, part order shuffled) for the footprints in the layout excerpt that follows; sources: Cadence DE-HDL packaged netlist, KiCad conversion of 03242023_DA0F0TMBIJ0_F0T_Motherboard_J_brd_V01_OCP.brd

C855  Q_CAP_DIFFBUS  DIFF BUS_0.22UF 6.3V 20% X6S  pkg C0201  page 174 : \1\ = P5E_CPU0_PE1_TX_C_DP<7> ; \2\ = P5E_CPU0_PE1_TX_DP<7>
PL19  Q_INDUCTOR  130NH/106A IND  pkg SMLF  page 289 : \1\ = SW_PVCCFA_EHV_FIVRA_CPU1_SW2 ; \2\ = PVCCFA_EHV_FIVRA_CPU1
R3946  Q_RES  0 5% EMPTY  pkg 0402LF  page 193 : A = E1S_0_EN ; B = P3V3_E1S_EN_0_R2

(kicad_pcb
	(version 20260206)
	(generator "pcbnew")
	(generator_version "10.0")
	(general
		(thickness 1.6)
		(legacy_teardrops no)
	)
	(paper "A4")
	(title_block
		(title "03242023_DA0F0TMBIJ0_F0T_Motherboard_J_brd_V01_OCP.brd")
		(comment 1 "Grand Teton / footprints 1395-1397 of 6105")
	)
	(layers
		(0 "F.Cu" signal "TOP")
		(4 "In1.Cu" signal "GND")
		(6 "In2.Cu" signal "IN1")
		(8 "In3.Cu" signal "GND1")
		(10 "In4.Cu" signal "IN2")
		(12 "In5.Cu" signal "GND2")
		(14 "In6.Cu" signal "IN3")
		(16 "In7.Cu" signal "GND3")
		(18 "In8.Cu" signal "VCC")
		(20 "In9.Cu" signal "VCC1")
		(22 "In10.Cu" signal "GND4")
		(24 "In11.Cu" signal "IN4")
		(26 "In12.Cu" signal "GND5")
		(28 "In13.Cu" signal "IN5")
		(30 "In14.Cu" signal "GND6")
		(32 "In15.Cu" signal "IN6")
		(34 "In16.Cu" signal "GND7")
		(2 "B.Cu" signal "BOTTOM")
		(9 "F.Adhes" user "F.Adhesive")
		(11 "B.Adhes" user "B.Adhesive")
		(13 "F.Paste" user "Package Geometry/Pastemask Top")
		(15 "B.Paste" user "Package Geometry/Pastemask Bottom")
		(5 "F.SilkS" user "Ref Des/Silkscreen Top")
		(7 "B.SilkS" user "Ref Des/Silkscreen Bottom")
		(1 "F.Mask" user "Board Geometry/Soldermask Top")
		(3 "B.Mask" user "Board Geometry/Soldermask Bottom")
		(17 "Dwgs.User" user "User.Drawings")
		(19 "Cmts.User" user "User.Comments")
		(21 "Eco1.User" user "User.Eco1")
		(23 "Eco2.User" user "User.Eco2")
		(25 "Edge.Cuts" user "Board Geometry/Outline")
		(27 "Margin" user)
		(31 "F.CrtYd" user "Package Geometry/Place Bound Top")
		(29 "B.CrtYd" user "Package Geometry/Place Bound Bottom")
		(35 "F.Fab" user "Ref Des/Assembly Top")
		(33 "B.Fab" user "Ref Des/Assembly Bottom")
	)
	(footprint ""
		(layer "F.Cu")
		(at 198.41464 -69.804788 180)
		(property "Reference" "R3946"
			(at 0 0 180)
			(layer "F.SilkS")
			(hide yes)
			(effects
				(font
					(size 1.27 1.27)
				)
			)
		)
		(property "Value" ""
			(at 0 0 180)
			(layer "F.Fab")
			(effects
				(font
					(size 1.27 1.27)
				)
			)
		)
		(duplicate_pad_numbers_are_jumpers no)
		(fp_line
			(start 0.7874 0.4064)
			(end -0.7874 0.4064)
			(stroke
				(width 0.1524)
				(type default)
			)
			(layer "F.SilkS")
		)
		(fp_line
			(start 0.7874 -0.4064)
			(end 0.7874 0.4064)
			(stroke
				(width 0.1524)
				(type default)
			)
			(layer "F.SilkS")
		)
		(fp_line
			(start -0.7874 0.4064)
			(end -0.7874 -0.4064)
			(stroke
				(width 0.1524)
				(type default)
			)
			(layer "F.SilkS")
		)
		(fp_line
			(start -0.7874 -0.4064)
			(end 0.7874 -0.4064)
			(stroke
				(width 0.1524)
				(type default)
			)
			(layer "F.SilkS")
		)
		(fp_line
			(start 0.67945 0.3048)
			(end 0.120396 0.3048)
			(stroke
				(width 0.1)
				(type default)
			)
			(layer "F.Fab")
		)
		(fp_line
			(start 0.67945 -0.3048)
			(end 0.67945 0.3048)
			(stroke
				(width 0.1)
				(type default)
			)
			(layer "F.Fab")
		)
		(fp_line
			(start 0.12065 -0.2794)
			(end 0.12065 -0.3048)
			(stroke
				(width 0.1)
				(type default)
			)
			(layer "F.Fab")
		)
		(fp_line
			(start 0.12065 -0.3048)
			(end 0.67945 -0.3048)
			(stroke
				(width 0.1)
				(type default)
			)
			(layer "F.Fab")
		)
		(fp_line
			(start 0.120396 0.3048)
			(end 0.120396 0.2794)
			(stroke
				(width 0.1)
				(type default)
			)
			(layer "F.Fab")
		)
		(fp_line
			(start 0.120396 0.2794)
			(end -0.12065 0.2794)
			(stroke
				(width 0.1)
				(type default)
			)
			(layer "F.Fab")
		)
		(fp_line
			(start -0.12065 0.3048)
			(end -0.67945 0.3048)
			(stroke
				(width 0.1)
				(type default)
			)
			(layer "F.Fab")
		)
		(fp_line
			(start -0.12065 0.2794)
			(end -0.12065 0.3048)
			(stroke
				(width 0.1)
				(type default)
			)
			(layer "F.Fab")
		)
		(fp_line
			(start -0.12065 -0.2794)
			(end 0.12065 -0.2794)
			(stroke
				(width 0.1)
				(type default)
			)
			(layer "F.Fab")
		)
		(fp_line
			(start -0.12065 -0.305054)
			(end -0.12065 -0.2794)
			(stroke
				(width 0.1)
				(type default)
			)
			(layer "F.Fab")
		)
		(fp_line
			(start -0.67945 0.3048)
			(end -0.67945 -0.305054)
			(stroke
				(width 0.1)
				(type default)
			)
			(layer "F.Fab")
		)
		(fp_line
			(start -0.67945 -0.305054)
			(end -0.12065 -0.305054)
			(stroke
				(width 0.1)
				(type default)
			)
			(layer "F.Fab")
		)
		(pad "1" smd circle
			(at -0.40005 0 180)
			(size 0 0)
			(layers "F.Cu" "F.Mask" "F.Paste")
			(net "E1S_0_EN")
		)
		(pad "2" smd circle
			(at 0.40005 0 180)
			(size 0 0)
			(layers "F.Cu" "F.Mask" "F.Paste")
			(net "P3V3_E1S_EN_0_R2")
		)
	)
	(footprint ""
		(layer "F.Cu")
		(at 51.251358 -344.77325 -90)
		(property "Reference" "PL19"
			(at -2.028698 4.869688 90)
			(unlocked yes)
			(layer "F.SilkS")
			(effects
				(font
					(size 0.7874 0.5842)
					(thickness 0.1524)
				)
				(justify left)
			)
		)
		(property "Value" ""
			(at 0 0 270)
			(layer "F.Fab")
			(effects
				(font
					(size 1.27 1.27)
				)
			)
		)
		(duplicate_pad_numbers_are_jumpers no)
		(fp_line
			(start -4.99999 3.750056)
			(end -4.99999 2.2479)
			(stroke
				(width 0.1524)
				(type default)
			)
			(layer "F.SilkS")
		)
		(fp_line
			(start 0 3.750056)
			(end -4.99999 3.750056)
			(stroke
				(width 0.1524)
				(type default)
			)
			(layer "F.SilkS")
		)
		(fp_line
			(start 4.99999 3.750056)
			(end 0 3.750056)
			(stroke
				(width 0.1524)
				(type default)
			)
			(layer "F.SilkS")
		)
		(fp_line
			(start 4.99999 2.2352)
			(end 4.99999 3.750056)
			(stroke
				(width 0.1524)
				(type default)
			)
			(layer "F.SilkS")
		)
		(fp_line
			(start -4.99999 -2.2479)
			(end -4.99999 -3.750056)
			(stroke
				(width 0.1524)
				(type default)
			)
			(layer "F.SilkS")
		)
		(fp_line
			(start -4.99999 -3.750056)
			(end 4.99999 -3.750056)
			(stroke
				(width 0.1524)
				(type default)
			)
			(layer "F.SilkS")
		)
		(fp_line
			(start 4.99999 -3.750056)
			(end 4.99999 -2.2479)
			(stroke
				(width 0.1524)
				(type default)
			)
			(layer "F.SilkS")
		)
		(fp_line
			(start -4.99999 3.750056)
			(end -4.99999 -3.750056)
			(stroke
				(width 0.1)
				(type default)
			)
			(layer "F.Fab")
		)
		(fp_line
			(start 0 3.750056)
			(end -4.99999 3.750056)
			(stroke
				(width 0.1)
				(type default)
			)
			(layer "F.Fab")
		)
		(fp_line
			(start 4.99999 3.750056)
			(end 0 3.750056)
			(stroke
				(width 0.1)
				(type default)
			)
			(layer "F.Fab")
		)
		(fp_line
			(start -4.99999 -3.750056)
			(end 4.99999 -3.750056)
			(stroke
				(width 0.1)
				(type default)
			)
			(layer "F.Fab")
		)
		(fp_line
			(start 4.99999 -3.750056)
			(end 4.99999 3.750056)
			(stroke
				(width 0.1)
				(type default)
			)
			(layer "F.Fab")
		)
		(pad "1" smd rect
			(at -3.299968 0 270)
			(size 3.302 4.2164)
			(layers "F.Cu" "F.Mask" "F.Paste")
			(net "SW_PVCCFA_EHV_FIVRA_CPU1_SW2")
		)
		(pad "2" smd rect
			(at 3.299968 0 270)
			(size 3.302 4.2164)
			(layers "F.Cu" "F.Mask" "F.Paste")
			(net "PVCCFA_EHV_FIVRA_CPU1")
		)
	)
	(footprint ""
		(layer "F.Cu")
		(at 412.367984 -16.088614 90)
		(property "Reference" "C855"
			(at 0 0 90)
			(layer "F.SilkS")
			(hide yes)
			(effects
				(font
					(size 1.27 1.27)
				)
			)
		)
		(property "Value" ""
			(at 0 0 90)
			(layer "F.Fab")
			(effects
				(font
					(size 1.27 1.27)
				)
			)
		)
		(duplicate_pad_numbers_are_jumpers no)
		(fp_line
			(start 0.299974 -0.150114)
			(end 0.299974 0.150114)
			(stroke
				(width 0.1)
				(type default)
			)
			(layer "F.Fab")
		)
		(fp_line
			(start -0.299974 -0.150114)
			(end 0.299974 -0.150114)
			(stroke
				(width 0.1)
				(type default)
			)
			(layer "F.Fab")
		)
		(fp_line
			(start 0.299974 0.150114)
			(end -0.299974 0.150114)
			(stroke
				(width 0.1)
				(type default)
			)
			(layer "F.Fab")
		)
		(fp_line
			(start -0.299974 0.150114)
			(end -0.299974 -0.150114)
			(stroke
				(width 0.1)
				(type default)
			)
			(layer "F.Fab")
		)
		(pad "1" smd rect
			(at -0.2667 0 90)
			(size 0.3048 0.381)
			(layers "F.Cu" "F.Mask" "F.Paste")
			(net "P5E_CPU0_PE1_TX_C_DP<7>")
		)
		(pad "2" smd rect
			(at 0.2667 0 90)
			(size 0.3048 0.381)
			(layers "F.Cu" "F.Mask" "F.Paste")
			(net "P5E_CPU0_PE1_TX_DP<7>")
		)
	)
)
